(kicad_pcb
	(version 20260206)
	(generator "pcbnew")
	(generator_version "10.0")
	(general
		(thickness 1.6)
		(legacy_teardrops no)
	)
	(paper "A4")
	(title_block
		(title "fcb — Lightning_FCB_BRD.brd")
		(comment 1 "Lightning (Wiwynn / Facebook NVMe JBOF) / footprints 392-399 of 495")
	)
	(layers
		(0 "F.Cu" signal "TOP")
		(4 "In1.Cu" signal "L2GND")
		(6 "In2.Cu" signal "L3VCC")
		(2 "B.Cu" signal "BOTTOM")
		(9 "F.Adhes" user "F.Adhesive")
		(11 "B.Adhes" user "B.Adhesive")
		(13 "F.Paste" user "Package Geometry/Pastemask Top")
		(15 "B.Paste" user "Package Geometry/Pastemask Bottom")
		(5 "F.SilkS" user "Ref Des/Silkscreen Top")
		(7 "B.SilkS" user "Ref Des/Silkscreen Bottom")
		(1 "F.Mask" user "Board Geometry/Soldermask Top")
		(3 "B.Mask" user "Board Geometry/Soldermask Bottom")
		(17 "Dwgs.User" user "User.Drawings")
		(19 "Cmts.User" user "User.Comments")
		(21 "Eco1.User" user "User.Eco1")
		(23 "Eco2.User" user "User.Eco2")
		(25 "Edge.Cuts" user "Board Geometry/Outline")
		(27 "Margin" user)
		(31 "F.CrtYd" user "Package Geometry/Place Bound Top")
		(29 "B.CrtYd" user "Package Geometry/Place Bound Bottom")
		(35 "F.Fab" user "Ref Des/Assembly Top")
		(33 "B.Fab" user "Ref Des/Assembly Bottom")
	)
	(footprint ""
		(layer "F.Cu")
		(at 29.7434 -363.2454 -90)
		(property "Reference" "TP22"
			(at 0 0 270)
			(layer "F.SilkS")
			(hide yes)
			(effects
				(font
					(size 1.27 1.27)
				)
			)
		)
		(property "Value" "TPAD32-GP"
			(at 0 -3.166364 270)
			(unlocked yes)
			(layer "F.Fab")
			(hide yes)
			(effects
				(font
					(size 1.016 1.016)
					(thickness 0.1524)
				)
			)
		)
		(property "Device Type" "TPAD32"
			(at 0 -4.690618 270)
			(unlocked yes)
			(layer "F.Fab")
			(hide yes)
			(effects
				(font
					(size 1.016 1.016)
					(thickness 0.1524)
				)
			)
		)
		(duplicate_pad_numbers_are_jumpers no)
		(fp_poly
			(pts
				(arc
					(start 0 -0.7112)
					(mid 0 0.7112)
					(end 0 -0.7112)
				)
			)
			(stroke
				(width 0)
				(type default)
			)
			(fill no)
			(layer "F.CrtYd")
		)
		(fp_poly
			(pts
				(arc
					(start 0 -0.7112)
					(mid 0 0.7112)
					(end 0 -0.7112)
				)
			)
			(stroke
				(width 0)
				(type default)
			)
			(fill no)
			(layer "F.Fab")
		)
		(pad "1" smd circle
			(at 0 0 270)
			(size 0.8128 0.8128)
			(layers "F.Cu" "F.Mask" "F.Paste")
			(net "ADM1276_GPIO2")
		)
	)
	(footprint ""
		(layer "F.Cu")
		(at 7.8232 -449.5546 90)
		(property "Reference" "R100"
			(at 0 0 90)
			(layer "F.SilkS")
			(hide yes)
			(effects
				(font
					(size 1.27 1.27)
				)
			)
		)
		(property "Value" "27KR3F-GP"
			(at -0.0254 -2.5146 90)
			(unlocked yes)
			(layer "F.Fab")
			(hide yes)
			(effects
				(font
					(size 1.016 1.016)
					(thickness 0.1524)
				)
			)
		)
		(property "Device Type" "R603H22"
			(at -0.0254 -4.0386 90)
			(unlocked yes)
			(layer "F.Fab")
			(hide yes)
			(effects
				(font
					(size 1.016 1.016)
					(thickness 0.1524)
				)
			)
		)
		(duplicate_pad_numbers_are_jumpers no)
		(fp_line
			(start 0.2032 0)
			(end 0.4826 0)
			(stroke
				(width 0.2032)
				(type default)
			)
			(layer "F.SilkS")
		)
		(fp_line
			(start -0.4826 0)
			(end -0.2032 0)
			(stroke
				(width 0.2032)
				(type default)
			)
			(layer "F.SilkS")
		)
		(fp_rect
			(start -0.5842 1.3335)
			(end 0.5842 -1.3335)
			(stroke
				(width 0)
				(type default)
			)
			(fill no)
			(layer "F.CrtYd")
		)
		(fp_rect
			(start -0.5842 1.3335)
			(end 0.5842 -1.3335)
			(stroke
				(width 0)
				(type default)
			)
			(fill no)
			(layer "F.Fab")
		)
		(pad "1" smd custom
			(at 0 -0.762 90)
			(size 0.2159 0.2159)
			(layers "F.Cu" "F.Mask" "F.Paste")
			(net "FANIN_1")
			(options
				(clearance outline)
				(anchor circle)
			)
			(primitives
				(gr_poly
					(pts
						(arc
							(start -0.3302 -0.4318)
							(mid -0.402042 -0.402042)
							(end -0.4318 -0.3302)
						)
						(arc
							(start -0.4318 0.3302)
							(mid -0.402042 0.402042)
							(end -0.3302 0.4318)
						)
						(arc
							(start 0.3302 0.4318)
							(mid 0.402042 0.402042)
							(end 0.4318 0.3302)
						)
						(arc
							(start 0.4318 -0.3302)
							(mid 0.402042 -0.402042)
							(end 0.3302 -0.4318)
						)
					)
					(width 0)
					(fill yes)
				)
			)
		)
		(pad "2" smd custom
			(at 0 0.762 90)
			(size 0.2159 0.2159)
			(layers "F.Cu" "F.Mask" "F.Paste")
			(net "FAN_TACH1")
			(options
				(clearance outline)
				(anchor circle)
			)
			(primitives
				(gr_poly
					(pts
						(arc
							(start -0.3302 -0.4318)
							(mid -0.402042 -0.402042)
							(end -0.4318 -0.3302)
						)
						(arc
							(start -0.4318 0.3302)
							(mid -0.402042 0.402042)
							(end -0.3302 0.4318)
						)
						(arc
							(start 0.3302 0.4318)
							(mid 0.402042 0.402042)
							(end 0.4318 0.3302)
						)
						(arc
							(start 0.4318 -0.3302)
							(mid 0.402042 -0.402042)
							(end 0.3302 -0.4318)
						)
					)
					(width 0)
					(fill yes)
				)
			)
		)
	)
	(footprint ""
		(layer "F.Cu")
		(at 25.5016 -139.5984 -90)
		(property "Reference" "PR99"
			(at 0 0 270)
			(layer "F.SilkS")
			(hide yes)
			(effects
				(font
					(size 1.27 1.27)
				)
			)
		)
		(property "Value" "100R2F-L1-GP-U"
			(at 0.064008 -3.993896 270)
			(unlocked yes)
			(layer "F.Fab")
			(hide yes)
			(effects
				(font
					(size 1.016 1.016)
					(thickness 0.1524)
				)
			)
		)
		(property "Device Type" "R402H14"
			(at 0.064008 -5.517896 270)
			(unlocked yes)
			(layer "F.Fab")
			(hide yes)
			(effects
				(font
					(size 1.016 1.016)
					(thickness 0.1524)
				)
			)
		)
		(duplicate_pad_numbers_are_jumpers no)
		(fp_line
			(start -0.508 -0.9398)
			(end -0.508 0.9398)
			(stroke
				(width 0.1524)
				(type default)
			)
			(layer "F.SilkS")
		)
		(fp_line
			(start 0.508 -0.9398)
			(end -0.508 -0.9398)
			(stroke
				(width 0.1524)
				(type default)
			)
			(layer "F.SilkS")
		)
		(fp_rect
			(start -0.508 0.9398)
			(end 0.508 -0.9398)
			(stroke
				(width 0)
				(type default)
			)
			(fill no)
			(layer "F.CrtYd")
		)
		(fp_rect
			(start -0.508 0.9398)
			(end 0.508 -0.9398)
			(stroke
				(width 0)
				(type default)
			)
			(fill no)
			(layer "F.Fab")
		)
		(pad "1" smd custom
			(at 0 -0.4445 270)
			(size 0.1397 0.1397)
			(layers "F.Cu" "F.Mask" "F.Paste")
			(net "P12VU_2490_GATE")
			(options
				(clearance outline)
				(anchor circle)
			)
			(primitives
				(gr_poly
					(pts
						(arc
							(start -0.1778 -0.2794)
							(mid -0.249642 -0.249642)
							(end -0.2794 -0.1778)
						)
						(arc
							(start -0.2794 0.1778)
							(mid -0.249642 0.249642)
							(end -0.1778 0.2794)
						)
						(arc
							(start 0.1778 0.2794)
							(mid 0.249642 0.249642)
							(end 0.2794 0.1778)
						)
						(arc
							(start 0.2794 -0.1778)
							(mid 0.249642 -0.249642)
							(end 0.1778 -0.2794)
						)
					)
					(width 0)
					(fill yes)
				)
			)
		)
		(pad "2" smd custom
			(at 0 0.4445 270)
			(size 0.1397 0.1397)
			(layers "F.Cu" "F.Mask" "F.Paste")
			(net "P12VU_2490_RC")
			(options
				(clearance outline)
				(anchor circle)
			)
			(primitives
				(gr_poly
					(pts
						(arc
							(start -0.1778 -0.2794)
							(mid -0.249642 -0.249642)
							(end -0.2794 -0.1778)
						)
						(arc
							(start -0.2794 0.1778)
							(mid -0.249642 0.249642)
							(end -0.1778 0.2794)
						)
						(arc
							(start 0.1778 0.2794)
							(mid 0.249642 0.249642)
							(end 0.2794 0.1778)
						)
						(arc
							(start 0.2794 -0.1778)
							(mid 0.249642 -0.249642)
							(end 0.1778 -0.2794)
						)
					)
					(width 0)
					(fill yes)
				)
			)
		)
	)
	(footprint ""
		(layer "F.Cu")
		(at 8.89 -148.1074 180)
		(property "Reference" "C28"
			(at 0 0 180)
			(layer "F.SilkS")
			(hide yes)
			(effects
				(font
					(size 1.27 1.27)
				)
			)
		)
		(property "Value" "SCD1U16V2KX-3GP"
			(at 1.1811 -2.7051 180)
			(unlocked yes)
			(layer "F.Fab")
			(hide yes)
			(effects
				(font
					(size 1.016 1.016)
					(thickness 0.1524)
				)
			)
		)
		(property "Device Type" "C402H22"
			(at 1.1811 -4.2291 180)
			(unlocked yes)
			(layer "F.Fab")
			(hide yes)
			(effects
				(font
					(size 1.016 1.016)
					(thickness 0.1524)
				)
			)
		)
		(duplicate_pad_numbers_are_jumpers no)
		(fp_rect
			(start -0.4318 0.9525)
			(end 0.4318 -0.9525)
			(stroke
				(width 0)
				(type default)
			)
			(fill no)
			(layer "F.CrtYd")
		)
		(fp_rect
			(start -0.4318 0.9525)
			(end 0.4318 -0.9525)
			(stroke
				(width 0)
				(type default)
			)
			(fill no)
			(layer "F.Fab")
		)
		(pad "1" smd custom
			(at 0 -0.4445 180)
			(size 0.1524 0.1524)
			(layers "F.Cu" "F.Mask" "F.Paste")
			(net "FAN_TACH10")
			(options
				(clearance outline)
				(anchor circle)
			)
			(primitives
				(gr_poly
					(pts
						(arc
							(start 0.3048 -0.2032)
							(mid 0.275042 -0.275042)
							(end 0.2032 -0.3048)
						)
						(arc
							(start -0.2032 -0.3048)
							(mid -0.275042 -0.275042)
							(end -0.3048 -0.2032)
						)
						(arc
							(start -0.3048 0.2032)
							(mid -0.275042 0.275042)
							(end -0.2032 0.3048)
						)
						(arc
							(start 0.2032 0.3048)
							(mid 0.275042 0.275042)
							(end 0.3048 0.2032)
						)
					)
					(width 0)
					(fill yes)
				)
			)
		)
		(pad "2" smd custom
			(at 0 0.4445 180)
			(size 0.1524 0.1524)
			(layers "F.Cu" "F.Mask" "F.Paste")
			(net "GND")
			(options
				(clearance outline)
				(anchor circle)
			)
			(primitives
				(gr_poly
					(pts
						(arc
							(start 0.3048 -0.2032)
							(mid 0.275042 -0.275042)
							(end 0.2032 -0.3048)
						)
						(arc
							(start -0.2032 -0.3048)
							(mid -0.275042 -0.275042)
							(end -0.3048 -0.2032)
						)
						(arc
							(start -0.3048 0.2032)
							(mid -0.275042 0.275042)
							(end -0.2032 0.3048)
						)
						(arc
							(start 0.2032 0.3048)
							(mid 0.275042 0.275042)
							(end 0.3048 0.2032)
						)
					)
					(width 0)
					(fill yes)
				)
			)
		)
	)
	(footprint ""
		(layer "F.Cu")
		(at 25.8826 -166.1414 180)
		(property "Reference" "TP5"
			(at 0 0 180)
			(layer "F.SilkS")
			(hide yes)
			(effects
				(font
					(size 1.27 1.27)
				)
			)
		)
		(property "Value" "TPAD32-GP"
			(at 0 -3.166364 180)
			(unlocked yes)
			(layer "F.Fab")
			(hide yes)
			(effects
				(font
					(size 1.016 1.016)
					(thickness 0.1524)
				)
			)
		)
		(property "Device Type" "TPAD32"
			(at 0 -4.690618 180)
			(unlocked yes)
			(layer "F.Fab")
			(hide yes)
			(effects
				(font
					(size 1.016 1.016)
					(thickness 0.1524)
				)
			)
		)
		(duplicate_pad_numbers_are_jumpers no)
		(fp_poly
			(pts
				(arc
					(start -0.7112 0)
					(mid 0.7112 0)
					(end -0.7112 0)
				)
			)
			(stroke
				(width 0)
				(type default)
			)
			(fill no)
			(layer "F.CrtYd")
		)
		(fp_poly
			(pts
				(arc
					(start -0.7112 0)
					(mid 0.7112 0)
					(end -0.7112 0)
				)
			)
			(stroke
				(width 0)
				(type default)
			)
			(fill no)
			(layer "F.Fab")
		)
		(pad "1" smd circle
			(at 0 0 180)
			(size 0.8128 0.8128)
			(layers "F.Cu" "F.Mask" "F.Paste")
			(net "NCT7904D_PWM4")
		)
	)
	(footprint ""
		(layer "F.Cu")
		(at 36.1188 -372.4656 -90)
		(property "Reference" "PR7"
			(at 0 0 270)
			(layer "F.SilkS")
			(hide yes)
			(effects
				(font
					(size 1.27 1.27)
				)
			)
		)
		(property "Value" "1KR2F-3-GP"
			(at 0.064008 -3.993896 270)
			(unlocked yes)
			(layer "F.Fab")
			(hide yes)
			(effects
				(font
					(size 1.016 1.016)
					(thickness 0.1524)
				)
			)
		)
		(property "Device Type" "R402H16"
			(at 0.064008 -5.517896 270)
			(unlocked yes)
			(layer "F.Fab")
			(hide yes)
			(effects
				(font
					(size 1.016 1.016)
					(thickness 0.1524)
				)
			)
		)
		(duplicate_pad_numbers_are_jumpers no)
		(fp_line
			(start -0.508 -0.9398)
			(end -0.508 0.9398)
			(stroke
				(width 0.1524)
				(type default)
			)
			(layer "F.SilkS")
		)
		(fp_line
			(start 0.508 -0.9398)
			(end -0.508 -0.9398)
			(stroke
				(width 0.1524)
				(type default)
			)
			(layer "F.SilkS")
		)
		(fp_rect
			(start -0.508 0.9398)
			(end 0.508 -0.9398)
			(stroke
				(width 0)
				(type default)
			)
			(fill no)
			(layer "F.CrtYd")
		)
		(fp_rect
			(start -0.508 0.9398)
			(end 0.508 -0.9398)
			(stroke
				(width 0)
				(type default)
			)
			(fill no)
			(layer "F.Fab")
		)
		(pad "1" smd custom
			(at 0 -0.4445 270)
			(size 0.1397 0.1397)
			(layers "F.Cu" "F.Mask" "F.Paste")
			(net "P12V")
			(options
				(clearance outline)
				(anchor circle)
			)
			(primitives
				(gr_poly
					(pts
						(arc
							(start -0.1778 -0.2794)
							(mid -0.249642 -0.249642)
							(end -0.2794 -0.1778)
						)
						(arc
							(start -0.2794 0.1778)
							(mid -0.249642 0.249642)
							(end -0.1778 0.2794)
						)
						(arc
							(start 0.1778 0.2794)
							(mid 0.249642 0.249642)
							(end 0.2794 0.1778)
						)
						(arc
							(start 0.2794 -0.1778)
							(mid 0.249642 -0.249642)
							(end 0.1778 -0.2794)
						)
					)
					(width 0)
					(fill yes)
				)
			)
		)
		(pad "2" smd custom
			(at 0 0.4445 270)
			(size 0.1397 0.1397)
			(layers "F.Cu" "F.Mask" "F.Paste")
			(net "ADM1276_VOUT")
			(options
				(clearance outline)
				(anchor circle)
			)
			(primitives
				(gr_poly
					(pts
						(arc
							(start -0.1778 -0.2794)
							(mid -0.249642 -0.249642)
							(end -0.2794 -0.1778)
						)
						(arc
							(start -0.2794 0.1778)
							(mid -0.249642 0.249642)
							(end -0.1778 0.2794)
						)
						(arc
							(start 0.1778 0.2794)
							(mid 0.249642 0.249642)
							(end 0.2794 0.1778)
						)
						(arc
							(start 0.2794 -0.1778)
							(mid 0.249642 -0.249642)
							(end 0.1778 -0.2794)
						)
					)
					(width 0)
					(fill yes)
				)
			)
		)
	)
	(footprint ""
		(layer "F.Cu")
		(at 29.972 -361.315 180)
		(property "Reference" "PR15"
			(at 0 0 180)
			(layer "F.SilkS")
			(hide yes)
			(effects
				(font
					(size 1.27 1.27)
				)
			)
		)
		(property "Value" "4K7R2J-2-GP"
			(at 0.064008 -3.993896 180)
			(unlocked yes)
			(layer "F.Fab")
			(hide yes)
			(effects
				(font
					(size 1.016 1.016)
					(thickness 0.1524)
				)
			)
		)
		(property "Device Type" "R402H16"
			(at 0.064008 -5.517896 180)
			(unlocked yes)
			(layer "F.Fab")
			(hide yes)
			(effects
				(font
					(size 1.016 1.016)
					(thickness 0.1524)
				)
			)
		)
		(duplicate_pad_numbers_are_jumpers no)
		(fp_line
			(start 0.508 -0.9398)
			(end -0.508 -0.9398)
			(stroke
				(width 0.1524)
				(type default)
			)
			(layer "F.SilkS")
		)
		(fp_line
			(start -0.508 -0.9398)
			(end -0.508 0.9398)
			(stroke
				(width 0.1524)
				(type default)
			)
			(layer "F.SilkS")
		)
		(fp_rect
			(start -0.508 0.9398)
			(end 0.508 -0.9398)
			(stroke
				(width 0)
				(type default)
			)
			(fill no)
			(layer "F.CrtYd")
		)
		(fp_rect
			(start -0.508 0.9398)
			(end 0.508 -0.9398)
			(stroke
				(width 0)
				(type default)
			)
			(fill no)
			(layer "F.Fab")
		)
		(pad "1" smd custom
			(at 0 -0.4445 180)
			(size 0.1397 0.1397)
			(layers "F.Cu" "F.Mask" "F.Paste")
			(net "P3V3")
			(options
				(clearance outline)
				(anchor circle)
			)
			(primitives
				(gr_poly
					(pts
						(arc
							(start -0.1778 -0.2794)
							(mid -0.249642 -0.249642)
							(end -0.2794 -0.1778)
						)
						(arc
							(start -0.2794 0.1778)
							(mid -0.249642 0.249642)
							(end -0.1778 0.2794)
						)
						(arc
							(start 0.1778 0.2794)
							(mid 0.249642 0.249642)
							(end 0.2794 0.1778)
						)
						(arc
							(start 0.2794 -0.1778)
							(mid 0.249642 -0.249642)
							(end 0.1778 -0.2794)
						)
					)
					(width 0)
					(fill yes)
				)
			)
		)
		(pad "2" smd custom
			(at 0 0.4445 180)
			(size 0.1397 0.1397)
			(layers "F.Cu" "F.Mask" "F.Paste")
			(net "ADM1276_GPIO2")
			(options
				(clearance outline)
				(anchor circle)
			)
			(primitives
				(gr_poly
					(pts
						(arc
							(start -0.1778 -0.2794)
							(mid -0.249642 -0.249642)
							(end -0.2794 -0.1778)
						)
						(arc
							(start -0.2794 0.1778)
							(mid -0.249642 0.249642)
							(end -0.1778 0.2794)
						)
						(arc
							(start 0.1778 0.2794)
							(mid 0.249642 0.249642)
							(end 0.2794 0.1778)
						)
						(arc
							(start 0.2794 -0.1778)
							(mid 0.249642 -0.249642)
							(end 0.1778 -0.2794)
						)
					)
					(width 0)
					(fill yes)
				)
			)
		)
	)
	(footprint ""
		(layer "F.Cu")
		(at 40.386 -370.332 -90)
		(property "Reference" "PR48"
			(at 0 0 270)
			(layer "F.SilkS")
			(hide yes)
			(effects
				(font
					(size 1.27 1.27)
				)
			)
		)
		(property "Value" "5K1R2F-2-GP"
			(at 0.064008 -3.993896 270)
			(unlocked yes)
			(layer "F.Fab")
			(hide yes)
			(effects
				(font
					(size 1.016 1.016)
					(thickness 0.1524)
				)
			)
		)
		(property "Device Type" "R402H16"
			(at 0.064008 -5.517896 270)
			(unlocked yes)
			(layer "F.Fab")
			(hide yes)
			(effects
				(font
					(size 1.016 1.016)
					(thickness 0.1524)
				)
			)
		)
		(duplicate_pad_numbers_are_jumpers no)
		(fp_line
			(start -0.508 -0.9398)
			(end -0.508 0.9398)
			(stroke
				(width 0.1524)
				(type default)
			)
			(layer "F.SilkS")
		)
		(fp_line
			(start 0.508 -0.9398)
			(end -0.508 -0.9398)
			(stroke
				(width 0.1524)
				(type default)
			)
			(layer "F.SilkS")
		)
		(fp_rect
			(start -0.508 0.9398)
			(end 0.508 -0.9398)
			(stroke
				(width 0)
				(type default)
			)
			(fill no)
			(layer "F.CrtYd")
		)
		(fp_rect
			(start -0.508 0.9398)
			(end 0.508 -0.9398)
			(stroke
				(width 0)
				(type default)
			)
			(fill no)
			(layer "F.Fab")
		)
		(pad "1" smd custom
			(at 0 -0.4445 270)
			(size 0.1397 0.1397)
			(layers "F.Cu" "F.Mask" "F.Paste")
			(net "ADM1276_EN_NET")
			(options
				(clearance outline)
				(anchor circle)
			)
			(primitives
				(gr_poly
					(pts
						(arc
							(start -0.1778 -0.2794)
							(mid -0.249642 -0.249642)
							(end -0.2794 -0.1778)
						)
						(arc
							(start -0.2794 0.1778)
							(mid -0.249642 0.249642)
							(end -0.1778 0.2794)
						)
						(arc
							(start 0.1778 0.2794)
							(mid 0.249642 0.249642)
							(end 0.2794 0.1778)
						)
						(arc
							(start 0.2794 -0.1778)
							(mid 0.249642 -0.249642)
							(end 0.1778 -0.2794)
						)
					)
					(width 0)
					(fill yes)
				)
			)
		)
		(pad "2" smd custom
			(at 0 0.4445 270)
			(size 0.1397 0.1397)
			(layers "F.Cu" "F.Mask" "F.Paste")
			(net "ADM1276_LATCH_B")
			(options
				(clearance outline)
				(anchor circle)
			)
			(primitives
				(gr_poly
					(pts
						(arc
							(start -0.1778 -0.2794)
							(mid -0.249642 -0.249642)
							(end -0.2794 -0.1778)
						)
						(arc
							(start -0.2794 0.1778)
							(mid -0.249642 0.249642)
							(end -0.1778 0.2794)
						)
						(arc
							(start 0.1778 0.2794)
							(mid 0.249642 0.249642)
							(end 0.2794 0.1778)
						)
						(arc
							(start 0.2794 -0.1778)
							(mid 0.249642 -0.249642)
							(end 0.1778 -0.2794)
						)
					)
					(width 0)
					(fill yes)
				)
			)
		)
	)
)
